(kicad_pcb
	(version 20241229)
	(generator "pcbnew")
	(generator_version "9.0")
	(general
		(thickness 1.294)
		(legacy_teardrops no)
	)
	(paper "A3")
	(title_block
		(title "Kintex 410T devboard")
		(date "2024-04-03")
		(rev "1.1.2")
		(comment 9 "footprint 170 of 975 (U1), pads 851-900 of 900")
	)
	(layers
		(0 "F.Cu" mixed)
		(4 "In1.Cu" power)
		(6 "In2.Cu" power)
		(8 "In3.Cu" mixed)
		(10 "In4.Cu" power)
		(12 "In5.Cu" mixed)
		(14 "In6.Cu" power)
		(16 "In7.Cu" mixed)
		(18 "In8.Cu" power)
		(2 "B.Cu" mixed)
		(9 "F.Adhes" user "F.Adhesive")
		(11 "B.Adhes" user "B.Adhesive")
		(13 "F.Paste" user)
		(15 "B.Paste" user)
		(5 "F.SilkS" user "F.Silkscreen")
		(7 "B.SilkS" user "B.Silkscreen")
		(1 "F.Mask" user)
		(3 "B.Mask" user)
		(17 "Dwgs.User" user "User.Drawings")
		(19 "Cmts.User" user "User.Comments")
		(21 "Eco1.User" user "User.Eco1")
		(23 "Eco2.User" user "User.Eco2")
		(25 "Edge.Cuts" user)
		(27 "Margin" user)
		(31 "F.CrtYd" user "F.Courtyard")
		(29 "B.CrtYd" user "B.Courtyard")
		(35 "F.Fab" user)
		(33 "B.Fab" user)
	)
	(footprint "antmicro-footprints:BGA-900_31x31mm_Layout30x30_P1x1mm_FFG900"
		(locked yes)
		(layer "F.Cu")
		(at 200 130)
		(property "Reference" "U1"
			(at -15.74 -15.78 0)
			(layer "F.SilkS")
			(effects
				(font
					(size 0.7 0.7)
					(thickness 0.15)
				)
				(justify left bottom)
			)
		)
		(property "Value" "XC7K410T-2FFG900I"
			(at -4.436 17.635 0)
			(layer "F.Fab")
			(effects
				(font
					(size 0.7 0.7)
					(thickness 0.15)
				)
				(justify left bottom)
			)
		)
		(property "Description" "FPGA, Kintex-7, MMCM, PLL, 350 I/O's, 710 MHz, 406720 Cells, 970 mV to 1.03 V, FCBGA-900"
			(at 0 0 0)
			(layer "F.Fab")
			(hide yes)
			(effects
				(font
					(size 1.27 1.27)
					(thickness 0.15)
				)
			)
		)
		(property "Author" "Antmicro"
			(at 0 0 0)
			(layer "F.Fab")
			(hide yes)
			(effects
				(font
					(size 1 1)
					(thickness 0.15)
				)
			)
		)
		(property "License" "Apache-2.0"
			(at 0 0 0)
			(layer "F.Fab")
			(hide yes)
			(effects
				(font
					(size 1 1)
					(thickness 0.15)
				)
			)
		)
		(property "MPN" "XC7K410T-2FFG900I"
			(at 0 0 0)
			(layer "F.Fab")
			(hide yes)
			(effects
				(font
					(size 1 1)
					(thickness 0.15)
				)
			)
		)
		(property "Manufacturer" "AMD-Xilinx"
			(at 0 0 0)
			(layer "F.Fab")
			(hide yes)
			(effects
				(font
					(size 1 1)
					(thickness 0.15)
				)
			)
		)
		(sheetname "FPGA supply")
		(sheetfile "fpga-supply.kicad_sch")
		(attr smd)
		(pad "W11" smd circle
			(at -4.5 3.5)
			(size 0.5 0.5)
			(property pad_prop_bga)
			(layers "F.Cu" "F.Mask" "F.Paste")
			(net 1 "GND")
			(pinfunction "GND")
			(pintype "passive")
			(solder_mask_margin 0.02)
		)
		(pad "W12" smd circle
			(at -3.5 3.5)
			(size 0.5 0.5)
			(property pad_prop_bga)
			(layers "F.Cu" "F.Mask" "F.Paste")
			(net 26 "+1V8")
			(pinfunction "VCCAUX_IO_G0")
			(pintype "passive")
			(solder_mask_margin 0.02)
		)
		(pad "W13" smd circle
			(at -2.5 3.5)
			(size 0.5 0.5)
			(property pad_prop_bga)
			(layers "F.Cu" "F.Mask" "F.Paste")
			(net 1 "GND")
			(pinfunction "GND")
			(pintype "passive")
			(solder_mask_margin 0.02)
		)
		(pad "W14" smd circle
			(at -1.5 3.5)
			(size 0.5 0.5)
			(property pad_prop_bga)
			(layers "F.Cu" "F.Mask" "F.Paste")
			(net 26 "+1V8")
			(pinfunction "VCCAUX")
			(pintype "passive")
			(solder_mask_margin 0.02)
		)
		(pad "W15" smd circle
			(at -0.5 3.5)
			(size 0.5 0.5)
			(property pad_prop_bga)
			(layers "F.Cu" "F.Mask" "F.Paste")
			(net 1 "GND")
			(pinfunction "GND")
			(pintype "passive")
			(solder_mask_margin 0.02)
		)
		(pad "W16" smd circle
			(at 0.5 3.5)
			(size 0.5 0.5)
			(property pad_prop_bga)
			(layers "F.Cu" "F.Mask" "F.Paste")
			(net 650 "+1V0")
			(pinfunction "VCCBRAM")
			(pintype "passive")
			(solder_mask_margin 0.02)
		)
		(pad "W17" smd circle
			(at 1.5 3.5)
			(size 0.5 0.5)
			(property pad_prop_bga)
			(layers "F.Cu" "F.Mask" "F.Paste")
			(net 1 "GND")
			(pinfunction "GND")
			(pintype "passive")
			(solder_mask_margin 0.02)
		)
		(pad "W18" smd circle
			(at 2.5 3.5)
			(size 0.5 0.5)
			(property pad_prop_bga)
			(layers "F.Cu" "F.Mask" "F.Paste")
			(net 650 "+1V0")
			(pinfunction "VCCINT")
			(pintype "passive")
			(solder_mask_margin 0.02)
		)
		(pad "W19" smd circle
			(at 3.5 3.5)
			(size 0.5 0.5)
			(property pad_prop_bga)
			(layers "F.Cu" "F.Mask" "F.Paste")
			(net 1049 "unconnected-(U1B-IO_25_14-PadW19)")
			(pinfunction "IO_25_14")
			(pintype "bidirectional+no_connect")
			(die_length 6.678)
			(solder_mask_margin 0.02)
		)
		(pad "W20" smd circle
			(at 4.5 3.5)
			(size 0.5 0.5)
			(property pad_prop_bga)
			(layers "F.Cu" "F.Mask" "F.Paste")
			(net 1 "GND")
			(pinfunction "GND")
			(pintype "passive")
			(solder_mask_margin 0.02)
		)
		(pad "W21" smd circle
			(at 5.5 3.5)
			(size 0.5 0.5)
			(property pad_prop_bga)
			(layers "F.Cu" "F.Mask" "F.Paste")
			(net 688 "/DRAM + SRAM/SRAM.DQ2")
			(pinfunction "IO_L24P_T3_A01_D17_14")
			(pintype "bidirectional")
			(die_length 7.855)
			(solder_mask_margin 0.02)
		)
		(pad "W22" smd circle
			(at 6.5 3.5)
			(size 0.5 0.5)
			(property pad_prop_bga)
			(layers "F.Cu" "F.Mask" "F.Paste")
			(net 563 "/DRAM + SRAM/SRAM.~{WE}")
			(pinfunction "IO_L24N_T3_A00_D16_14")
			(pintype "bidirectional")
			(die_length 8.287)
			(solder_mask_margin 0.02)
		)
		(pad "W23" smd circle
			(at 7.5 3.5)
			(size 0.5 0.5)
			(property pad_prop_bga)
			(layers "F.Cu" "F.Mask" "F.Paste")
			(net 689 "/DRAM + SRAM/SRAM.A16")
			(pinfunction "IO_L20P_T3_A08_D24_14")
			(pintype "bidirectional")
			(die_length 8.317)
			(solder_mask_margin 0.02)
		)
		(pad "W24" smd circle
			(at 8.5 3.5)
			(size 0.5 0.5)
			(property pad_prop_bga)
			(layers "F.Cu" "F.Mask" "F.Paste")
			(net 690 "/DRAM + SRAM/SRAM.A17")
			(pinfunction "IO_L20N_T3_A07_D23_14")
			(pintype "bidirectional")
			(die_length 8.141)
			(solder_mask_margin 0.02)
		)
		(pad "W25" smd circle
			(at 9.5 3.5)
			(size 0.5 0.5)
			(property pad_prop_bga)
			(layers "F.Cu" "F.Mask" "F.Paste")
			(net 24 "+3V3")
			(pinfunction "VCCO_14")
			(pintype "passive")
			(solder_mask_margin 0.02)
		)
		(pad "W26" smd circle
			(at 10.5 3.5)
			(size 0.5 0.5)
			(property pad_prop_bga)
			(layers "F.Cu" "F.Mask" "F.Paste")
			(net 691 "/DRAM + SRAM/SRAM.A19")
			(pinfunction "IO_L18N_T2_A11_D27_14")
			(pintype "bidirectional")
			(die_length 11.963)
			(solder_mask_margin 0.02)
		)
		(pad "W27" smd circle
			(at 11.5 3.5)
			(size 0.5 0.5)
			(property pad_prop_bga)
			(layers "F.Cu" "F.Mask" "F.Paste")
			(net 457 "/FPGA Bank 12 & 13/PMOD_A.IO2")
			(pinfunction "IO_L2P_T0_13")
			(pintype "bidirectional")
			(die_length 11.615)
			(solder_mask_margin 0.02)
		)
		(pad "W28" smd circle
			(at 12.5 3.5)
			(size 0.5 0.5)
			(property pad_prop_bga)
			(layers "F.Cu" "F.Mask" "F.Paste")
			(net 472 "/FPGA Bank 12 & 13/PMOD_B.IO4")
			(pinfunction "IO_L2N_T0_13")
			(pintype "bidirectional")
			(die_length 12.971)
			(solder_mask_margin 0.02)
		)
		(pad "W29" smd circle
			(at 13.5 3.5)
			(size 0.5 0.5)
			(property pad_prop_bga)
			(layers "F.Cu" "F.Mask" "F.Paste")
			(net 434 "/FPGA Bank 12 & 13/PMOD_A.IO8")
			(pinfunction "IO_L4P_T0_13")
			(pintype "bidirectional")
			(die_length 14.012)
			(solder_mask_margin 0.02)
		)
		(pad "W30" smd circle
			(at 14.5 3.5)
			(size 0.5 0.5)
			(property pad_prop_bga)
			(layers "F.Cu" "F.Mask" "F.Paste")
			(net 1 "GND")
			(pinfunction "GND")
			(pintype "passive")
			(solder_mask_margin 0.02)
		)
		(pad "Y1" smd circle
			(at -14.5 4.5)
			(size 0.5 0.5)
			(property pad_prop_bga)
			(layers "F.Cu" "F.Mask" "F.Paste")
			(net 101 "/FMC+ HSPC/GTX115.TX2_N")
			(pinfunction "MGTXTXN0_115")
			(pintype "bidirectional")
			(die_length 15.513)
			(solder_mask_margin 0.02)
		)
		(pad "Y2" smd circle
			(at -13.5 4.5)
			(size 0.5 0.5)
			(property pad_prop_bga)
			(layers "F.Cu" "F.Mask" "F.Paste")
			(net 97 "/FMC+ HSPC/GTX115.TX2_P")
			(pinfunction "MGTXTXP0_115")
			(pintype "bidirectional")
			(die_length 15.611)
			(solder_mask_margin 0.02)
		)
		(pad "Y3" smd circle
			(at -12.5 4.5)
			(size 0.5 0.5)
			(property pad_prop_bga)
			(layers "F.Cu" "F.Mask" "F.Paste")
			(net 1 "GND")
			(pinfunction "GND")
			(pintype "passive")
			(solder_mask_margin 0.02)
		)
		(pad "Y4" smd circle
			(at -11.5 4.5)
			(size 0.5 0.5)
			(property pad_prop_bga)
			(layers "F.Cu" "F.Mask" "F.Paste")
			(net 1 "GND")
			(pinfunction "GND")
			(pintype "passive")
			(solder_mask_margin 0.02)
		)
		(pad "Y5" smd circle
			(at -10.5 4.5)
			(size 0.5 0.5)
			(property pad_prop_bga)
			(layers "F.Cu" "F.Mask" "F.Paste")
			(net 463 "/FMC+ HSPC/GTX115.RX1_N")
			(pinfunction "MGTXRXN1_115")
			(pintype "bidirectional")
			(die_length 14.381)
			(solder_mask_margin 0.02)
		)
		(pad "Y6" smd circle
			(at -9.5 4.5)
			(size 0.5 0.5)
			(property pad_prop_bga)
			(layers "F.Cu" "F.Mask" "F.Paste")
			(net 468 "/FMC+ HSPC/GTX115.RX1_P")
			(pinfunction "MGTXRXP1_115")
			(pintype "bidirectional")
			(die_length 14.366)
			(solder_mask_margin 0.02)
		)
		(pad "Y7" smd circle
			(at -8.5 4.5)
			(size 0.5 0.5)
			(property pad_prop_bga)
			(layers "F.Cu" "F.Mask" "F.Paste")
			(net 1 "GND")
			(pinfunction "GND")
			(pintype "passive")
			(solder_mask_margin 0.02)
		)
		(pad "Y8" smd circle
			(at -7.5 4.5)
			(size 0.5 0.5)
			(property pad_prop_bga)
			(layers "F.Cu" "F.Mask" "F.Paste")
			(net 1 "GND")
			(pinfunction "GND")
			(pintype "passive")
			(solder_mask_margin 0.02)
		)
		(pad "Y9" smd circle
			(at -6.5 4.5)
			(size 0.5 0.5)
			(property pad_prop_bga)
			(layers "F.Cu" "F.Mask" "F.Paste")
			(net 1 "GND")
			(pinfunction "GND")
			(pintype "passive")
			(solder_mask_margin 0.02)
		)
		(pad "Y10" smd circle
			(at -5.5 4.5)
			(size 0.5 0.5)
			(property pad_prop_bga)
			(layers "F.Cu" "F.Mask" "F.Paste")
			(net 1233 "/USER_IO.BUTTON2")
			(pinfunction "IO_L4N_T0_33")
			(pintype "bidirectional")
			(die_length 9.48)
			(solder_mask_margin 0.02)
		)
		(pad "Y11" smd circle
			(at -4.5 4.5)
			(size 0.5 0.5)
			(property pad_prop_bga)
			(layers "F.Cu" "F.Mask" "F.Paste")
			(net 1232 "/USER_IO.BUTTON3")
			(pinfunction "IO_L4P_T0_33")
			(pintype "bidirectional")
			(die_length 7.911)
			(solder_mask_margin 0.02)
		)
		(pad "Y12" smd circle
			(at -3.5 4.5)
			(size 0.5 0.5)
			(property pad_prop_bga)
			(layers "F.Cu" "F.Mask" "F.Paste")
			(net 26 "+1V8")
			(pinfunction "VCCO_33")
			(pintype "passive")
			(solder_mask_margin 0.02)
		)
		(pad "Y13" smd circle
			(at -2.5 4.5)
			(size 0.5 0.5)
			(property pad_prop_bga)
			(layers "F.Cu" "F.Mask" "F.Paste")
			(net 1311 "/USER_IO.DIP_SW0")
			(pinfunction "IO_0_VRN_33")
			(pintype "bidirectional")
			(die_length 7.67)
			(solder_mask_margin 0.02)
		)
		(pad "Y14" smd circle
			(at -1.5 4.5)
			(size 0.5 0.5)
			(property pad_prop_bga)
			(layers "F.Cu" "F.Mask" "F.Paste")
			(net 1397 "/FPGA Bank 12 & 13/USB_USER.VM")
			(pinfunction "IO_0_VRN_32")
			(pintype "bidirectional")
			(die_length 12.537)
			(solder_mask_margin 0.02)
		)
		(pad "Y15" smd circle
			(at -0.5 4.5)
			(size 0.5 0.5)
			(property pad_prop_bga)
			(layers "F.Cu" "F.Mask" "F.Paste")
			(net 1398 "unconnected-(U1D-IO_L24N_T3_32-PadY15)")
			(pinfunction "IO_L24N_T3_32")
			(pintype "bidirectional+no_connect")
			(die_length 15.861)
			(solder_mask_margin 0.02)
		)
		(pad "Y16" smd circle
			(at 0.5 4.5)
			(size 0.5 0.5)
			(property pad_prop_bga)
			(layers "F.Cu" "F.Mask" "F.Paste")
			(net 1399 "unconnected-(U1D-IO_L24P_T3_32-PadY16)")
			(pinfunction "IO_L24P_T3_32")
			(pintype "bidirectional+no_connect")
			(die_length 14.497)
			(solder_mask_margin 0.02)
		)
		(pad "Y17" smd circle
			(at 1.5 4.5)
			(size 0.5 0.5)
			(property pad_prop_bga)
			(layers "F.Cu" "F.Mask" "F.Paste")
			(net 1 "GND")
			(pinfunction "GND")
			(pintype "passive")
			(solder_mask_margin 0.02)
		)
		(pad "Y18" smd circle
			(at 2.5 4.5)
			(size 0.5 0.5)
			(property pad_prop_bga)
			(layers "F.Cu" "F.Mask" "F.Paste")
			(net 1400 "unconnected-(U1D-IO_L15N_T2_DQS_32-PadY18)")
			(pinfunction "IO_L15N_T2_DQS_32")
			(pintype "bidirectional+no_connect")
			(die_length 23.661)
			(solder_mask_margin 0.02)
		)
		(pad "Y19" smd circle
			(at 3.5 4.5)
			(size 0.5 0.5)
			(property pad_prop_bga)
			(layers "F.Cu" "F.Mask" "F.Paste")
			(net 521 "/FPGA Bank 18 & 32/ETH_RMII.RXER")
			(pinfunction "IO_L15P_T2_DQS_32")
			(pintype "bidirectional")
			(die_length 23.666)
			(solder_mask_margin 0.02)
		)
		(pad "Y20" smd circle
			(at 4.5 4.5)
			(size 0.5 0.5)
			(property pad_prop_bga)
			(layers "F.Cu" "F.Mask" "F.Paste")
			(net 1355 "/SUP_MCU.A16")
			(pinfunction "IO_0_12")
			(pintype "bidirectional")
			(die_length 8.993)
			(solder_mask_margin 0.02)
		)
		(pad "Y21" smd circle
			(at 5.5 4.5)
			(size 0.5 0.5)
			(property pad_prop_bga)
			(layers "F.Cu" "F.Mask" "F.Paste")
			(net 1352 "/SUP_MCU.A13")
			(pinfunction "IO_L2P_T0_12")
			(pintype "bidirectional")
			(die_length 9.039)
			(solder_mask_margin 0.02)
		)
		(pad "Y22" smd circle
			(at 6.5 4.5)
			(size 0.5 0.5)
			(property pad_prop_bga)
			(layers "F.Cu" "F.Mask" "F.Paste")
			(net 24 "+3V3")
			(pinfunction "VCCO_12")
			(pintype "passive")
			(solder_mask_margin 0.02)
		)
		(pad "Y23" smd circle
			(at 7.5 4.5)
			(size 0.5 0.5)
			(property pad_prop_bga)
			(layers "F.Cu" "F.Mask" "F.Paste")
			(net 1366 "/SUP_MCU.A14")
			(pinfunction "IO_L1P_T0_12")
			(pintype "bidirectional")
			(die_length 10.411)
			(solder_mask_margin 0.02)
		)
		(pad "Y24" smd circle
			(at 8.5 4.5)
			(size 0.5 0.5)
			(property pad_prop_bga)
			(layers "F.Cu" "F.Mask" "F.Paste")
			(net 1364 "/SUP_MCU.A15")
			(pinfunction "IO_L1N_T0_12")
			(pintype "bidirectional")
			(die_length 11.014)
			(solder_mask_margin 0.02)
		)
		(pad "Y25" smd circle
			(at 9.5 4.5)
			(size 0.5 0.5)
			(property pad_prop_bga)
			(layers "F.Cu" "F.Mask" "F.Paste")
			(net 1401 "unconnected-(U1A-IO_0_13-PadY25)")
			(pinfunction "IO_0_13")
			(pintype "bidirectional+no_connect")
			(die_length 9.219)
			(solder_mask_margin 0.02)
		)
		(pad "Y26" smd circle
			(at 10.5 4.5)
			(size 0.5 0.5)
			(property pad_prop_bga)
			(layers "F.Cu" "F.Mask" "F.Paste")
			(net 1304 "/USER_IO.LED_GREEN5")
			(pinfunction "IO_L1P_T0_13")
			(pintype "bidirectional")
			(die_length 11.658)
			(solder_mask_margin 0.02)
		)
		(pad "Y27" smd circle
			(at 11.5 4.5)
			(size 0.5 0.5)
			(property pad_prop_bga)
			(layers "F.Cu" "F.Mask" "F.Paste")
			(net 1 "GND")
			(pinfunction "GND")
			(pintype "passive")
			(solder_mask_margin 0.02)
		)
		(pad "Y28" smd circle
			(at 12.5 4.5)
			(size 0.5 0.5)
			(property pad_prop_bga)
			(layers "F.Cu" "F.Mask" "F.Paste")
			(net 1305 "/USER_IO.LED_RED")
			(pinfunction "IO_L3P_T0_DQS_13")
			(pintype "bidirectional")
			(die_length 14.559)
			(solder_mask_margin 0.02)
		)
		(pad "Y29" smd circle
			(at 13.5 4.5)
			(size 0.5 0.5)
			(property pad_prop_bga)
			(layers "F.Cu" "F.Mask" "F.Paste")
			(net 1053 "/DC-DC Converters/PB_CTRL.VDDR_EN")
			(pinfunction "IO_L4N_T0_13")
			(pintype "bidirectional")
			(die_length 14.587)
			(solder_mask_margin 0.02)
		)
		(pad "Y30" smd circle
			(at 14.5 4.5)
			(size 0.5 0.5)
			(property pad_prop_bga)
			(layers "F.Cu" "F.Mask" "F.Paste")
			(net 1299 "/USER_IO.LED_GREEN0")
			(pinfunction "IO_L8P_T1_13")
			(pintype "bidirectional")
			(die_length 18.627)
			(solder_mask_margin 0.02)
		)
	)
)
